FILE_TYPE = MACRO_DRAWING;
SET COLOR_WIRE YELLOW;
SET COLOR_PROP ORANGE;
SET COLOR_DOT WHITE;
SET COLOR_ARC YELLOW;
SET COLOR_BODY GREEN;
SET COLOR_NOTE PURPLE;
SET PROP_DISPLAY VALUE;
SET PAGE_NUMBER P391;
FORCEADD VCC_CORE..1
(-5075 4575);
FORCEPROP 3 LASTPIN (-5075 4525) SIG_NAME P0V9_CPU1_RT1_2A_2D\g
J 0
(-5065 4535);
DISPLAY 0.659574 (-5065 4535);
PAINT MONO (-5065 4535);
DISPLAY INVISIBLE (-5065 4535);
FORCEPROP 1 LAST HDL_POWER P0V9_CPU1_RT1_2A_2D
J 1
(-5075 4625);
DISPLAY 0.617021 (-5075 4625);
PAINT GREEN (-5075 4625);
FORCEPROP 2 LAST CDS_LIB pure_quanta_power
J 0
(-5075 4575);
DISPLAY INVISIBLE (-5075 4575);
FORCEPROP 1 LAST PATH I10
J 0
(-5025 4600);
DISPLAY 0.872340 (-5025 4600);
PAINT AQUA (-5025 4600);
DISPLAY INVISIBLE (-5025 4600);
FORCEADD VCC_CORE..1
(-4500 5050);
FORCEPROP 3 LASTPIN (-4500 5000) SIG_NAME P0V9_CPU1_RT1_2A\g
J 0
(-4490 5010);
DISPLAY 0.659574 (-4490 5010);
PAINT MONO (-4490 5010);
DISPLAY INVISIBLE (-4490 5010);
FORCEPROP 1 LAST HDL_POWER P0V9_CPU1_RT1_2A
J 1
(-4500 5100);
DISPLAY 0.617021 (-4500 5100);
PAINT GREEN (-4500 5100);
FORCEPROP 2 LAST CDS_LIB pure_quanta_power
J 0
(-4500 5050);
DISPLAY INVISIBLE (-4500 5050);
FORCEPROP 1 LAST PATH I11
J 0
(-4450 5075);
DISPLAY 0.872340 (-4450 5075);
PAINT AQUA (-4450 5075);
DISPLAY INVISIBLE (-4450 5075);
FORCEADD UNIVERSAL_GND..1
(-2950 1350);
FORCEPROP 3 LASTPIN (-2950 1400) SIG_NAME GND\g
J 0
(-2940 1410);
DISPLAY 0.659574 (-2940 1410);
PAINT MONO (-2940 1410);
DISPLAY INVISIBLE (-2940 1410);
FORCEPROP 2 LAST CDS_LIB pure_quanta_power
J 0
(-2950 1350);
DISPLAY INVISIBLE (-2950 1350);
FORCEPROP 1 LAST HDL_POWER GND
J 1
(-2925 1275);
DISPLAY 0.872340 (-2925 1275);
PAINT GREEN (-2925 1275);
DISPLAY INVISIBLE (-2925 1275);
FORCEPROP 1 LAST PATH I12
J 0
(-2875 1350);
DISPLAY 0.872340 (-2875 1350);
PAINT AQUA (-2875 1350);
DISPLAY INVISIBLE (-2875 1350);
FORCEADD P1V0..1
(-4475 3825);
FORCEPROP 3 LASTPIN (-4475 3775) SIG_NAME P0V9_CPU1_RT_2D\g
J 0
(-4465 3785);
DISPLAY 0.659574 (-4465 3785);
PAINT MONO (-4465 3785);
DISPLAY INVISIBLE (-4465 3785);
FORCEPROP 1 LAST HDL_POWER P0V9_CPU1_RT_2D
J 1
(-4475 3875);
DISPLAY 0.489362 (-4475 3875);
PAINT SKYBLUE (-4475 3875);
FORCEPROP 2 LAST CDS_LIB pure_quanta_power
J 0
(-4475 3825);
DISPLAY INVISIBLE (-4475 3825);
FORCEPROP 1 LAST PATH I13
J 0
(-4425 3850);
DISPLAY 0.872340 (-4425 3850);
PAINT AQUA (-4425 3850);
DISPLAY INVISIBLE (-4425 3850);
FORCEADD UNIVERSAL_GND..1
(-1275 975);
FORCEPROP 3 LASTPIN (-1275 1025) SIG_NAME GND\g
J 0
(-1265 1035);
DISPLAY 0.659574 (-1265 1035);
PAINT MONO (-1265 1035);
DISPLAY INVISIBLE (-1265 1035);
FORCEPROP 2 LAST CDS_LIB pure_quanta_power
J 0
(-1275 975);
DISPLAY INVISIBLE (-1275 975);
FORCEPROP 1 LAST HDL_POWER GND
J 1
(-1250 900);
DISPLAY 0.872340 (-1250 900);
PAINT GREEN (-1250 900);
DISPLAY INVISIBLE (-1250 900);
FORCEPROP 1 LAST PATH I14
J 0
(-1200 975);
DISPLAY 0.872340 (-1200 975);
PAINT AQUA (-1200 975);
DISPLAY INVISIBLE (-1200 975);
FORCEADD Q_RES..2
(-1275 1275);
FORCEPROP 1 LAST LOCATION R6733
J 0
(-1230 1400);
DISPLAY 0.978723 (-1230 1400);
FORCEPROP 0 LAST $SEC 1
J 0
(-1225 1450);
DISPLAY 0.680851 (-1225 1450);
PAINT MONO (-1225 1450);
DISPLAY INVISIBLE (-1225 1450);
FORCEPROP 0 LAST CDS_SEC 1
J 0
(-1225 1450);
DISPLAY 0.680851 (-1225 1450);
DISPLAY INVISIBLE (-1225 1450);
FORCEPROP 1 LASTPIN (-1275 1375) $PN 1
J 0
(-1270 1337);
DISPLAY 0.787234 (-1270 1337);
PAINT MONO (-1270 1337);
FORCEPROP 1 LASTPIN (-1275 1175) $PN 2
J 0
(-1270 1185);
DISPLAY 0.787234 (-1270 1185);
PAINT MONO (-1270 1185);
FORCEPROP 1 LAST PACK_TYPE 0201LF
J 0
(-1235 1100);
DISPLAY 0.978723 (-1235 1100);
FORCEPROP 1 LAST VALUE 0
J 0
(-1230 1350);
DISPLAY 0.978723 (-1230 1350);
FORCEPROP 1 LAST TOLERANCE 5%
J 0
(-1230 1300);
DISPLAY 0.978723 (-1230 1300);
FORCEPROP 1 LAST MATERIAL CHIP
J 0
(-1235 1200);
DISPLAY 0.978723 (-1235 1200);
FORCEPROP 1 LAST WATTAGE 1/20W
J 0
(-1235 1250);
DISPLAY 0.978723 (-1235 1250);
FORCEPROP 2 LAST CDS_LIB pure_quanta
J 0
(-1275 1275);
DISPLAY INVISIBLE (-1275 1275);
FORCEPROP 1 LAST PATH I15
J 0
(-1225 1450);
DISPLAY 0.978723 (-1225 1450);
PAINT WHITE (-1225 1450);
DISPLAY INVISIBLE (-1225 1450);
FORCEPROP 1 LAST PART_NUMBER CS00001JE10
J 0
(-1235 1150);
DISPLAY 0.978723 (-1235 1150);
DISPLAY INVISIBLE (-1235 1150);
FORCEADD Q_RES..2
(-1125 1825);
FORCEPROP 1 LAST LOCATION R6732
J 0
(-1080 1950);
DISPLAY 0.978723 (-1080 1950);
FORCEPROP 0 LAST $SEC 1
J 0
(-1075 2000);
DISPLAY 0.680851 (-1075 2000);
PAINT MONO (-1075 2000);
DISPLAY INVISIBLE (-1075 2000);
FORCEPROP 0 LAST CDS_SEC 1
J 0
(-1075 2000);
DISPLAY 0.680851 (-1075 2000);
DISPLAY INVISIBLE (-1075 2000);
FORCEPROP 1 LASTPIN (-1125 1925) $PN 1
J 0
(-1120 1887);
DISPLAY 0.787234 (-1120 1887);
PAINT MONO (-1120 1887);
FORCEPROP 1 LASTPIN (-1125 1725) $PN 2
J 0
(-1120 1735);
DISPLAY 0.787234 (-1120 1735);
PAINT MONO (-1120 1735);
FORCEPROP 1 LAST PACK_TYPE 0201LF
J 0
(-1085 1650);
DISPLAY 0.978723 (-1085 1650);
FORCEPROP 1 LAST VALUE 0
J 0
(-1080 1900);
DISPLAY 0.978723 (-1080 1900);
FORCEPROP 1 LAST TOLERANCE 5%
J 0
(-1080 1850);
DISPLAY 0.978723 (-1080 1850);
FORCEPROP 1 LAST MATERIAL CHIP
J 0
(-1085 1750);
DISPLAY 0.978723 (-1085 1750);
FORCEPROP 1 LAST WATTAGE 1/20W
J 0
(-1085 1800);
DISPLAY 0.978723 (-1085 1800);
FORCEPROP 2 LAST CDS_LIB pure_quanta
J 0
(-1125 1825);
DISPLAY INVISIBLE (-1125 1825);
FORCEPROP 1 LAST PATH I16
J 0
(-1075 2000);
DISPLAY 0.978723 (-1075 2000);
PAINT WHITE (-1075 2000);
DISPLAY INVISIBLE (-1075 2000);
FORCEPROP 1 LAST PART_NUMBER CS00001JE10
J 0
(-1085 1700);
DISPLAY 0.978723 (-1085 1700);
DISPLAY INVISIBLE (-1085 1700);
FORCEADD UNIVERSAL_GND..1
(-900 2075);
FORCEPROP 3 LASTPIN (-900 2125) SIG_NAME GND\g
J 0
(-890 2135);
DISPLAY 0.659574 (-890 2135);
PAINT MONO (-890 2135);
DISPLAY INVISIBLE (-890 2135);
FORCEPROP 2 LAST CDS_LIB pure_quanta_power
J 0
(-900 2075);
DISPLAY INVISIBLE (-900 2075);
FORCEPROP 1 LAST HDL_POWER GND
J 1
(-875 2000);
DISPLAY 0.872340 (-875 2000);
PAINT GREEN (-875 2000);
DISPLAY INVISIBLE (-875 2000);
FORCEPROP 1 LAST PATH I17
J 0
(-825 2075);
DISPLAY 0.872340 (-825 2075);
PAINT AQUA (-825 2075);
DISPLAY INVISIBLE (-825 2075);
FORCEADD UNIVERSAL_GND..1
(-1125 1525);
FORCEPROP 3 LASTPIN (-1125 1575) SIG_NAME GND\g
J 0
(-1115 1585);
DISPLAY 0.659574 (-1115 1585);
PAINT MONO (-1115 1585);
DISPLAY INVISIBLE (-1115 1585);
FORCEPROP 2 LAST CDS_LIB pure_quanta_power
J 0
(-1125 1525);
DISPLAY INVISIBLE (-1125 1525);
FORCEPROP 1 LAST HDL_POWER GND
J 1
(-1100 1450);
DISPLAY 0.872340 (-1100 1450);
PAINT GREEN (-1100 1450);
DISPLAY INVISIBLE (-1100 1450);
FORCEPROP 1 LAST PATH I18
J 0
(-1050 1525);
DISPLAY 0.872340 (-1050 1525);
PAINT AQUA (-1050 1525);
DISPLAY INVISIBLE (-1050 1525);
FORCEADD PT5161LRS..5
(-2250 3600);
FORCEPROP 1 LAST LOCATION U6015
J 0
(-2600 5925);
DISPLAY 0.723404 (-2600 5925);
PAINT GREEN (-2600 5925);
FORCEPROP 0 LAST $SEC 5
J 0
(-2600 6075);
DISPLAY 0.680851 (-2600 6075);
PAINT MONO (-2600 6075);
DISPLAY INVISIBLE (-2600 6075);
FORCEPROP 0 LAST CDS_SEC 5
J 0
(-2600 6075);
DISPLAY 0.680851 (-2600 6075);
DISPLAY INVISIBLE (-2600 6075);
FORCEPROP 0 LASTPIN (-2750 5600) $PN AC13
J 2
(-2760 5610);
DISPLAY 0.680851 (-2760 5610);
PAINT MONO (-2760 5610);
FORCEPROP 0 LASTPIN (-2750 5550) $PN AC22
J 2
(-2760 5560);
DISPLAY 0.680851 (-2760 5560);
PAINT MONO (-2760 5560);
FORCEPROP 0 LASTPIN (-2750 5500) $PN AC32
J 2
(-2760 5510);
DISPLAY 0.680851 (-2760 5510);
PAINT MONO (-2760 5510);
FORCEPROP 0 LASTPIN (-2750 5450) $PN AC4
J 2
(-2760 5460);
DISPLAY 0.680851 (-2760 5460);
PAINT MONO (-2760 5460);
FORCEPROP 0 LASTPIN (-2750 5400) $PN AD2
J 2
(-2760 5410);
DISPLAY 0.680851 (-2760 5410);
PAINT MONO (-2760 5410);
FORCEPROP 0 LASTPIN (-2750 5350) $PN AD34
J 2
(-2760 5360);
DISPLAY 0.680851 (-2760 5360);
PAINT MONO (-2760 5360);
FORCEPROP 0 LASTPIN (-2750 5300) $PN AE1
J 2
(-2760 5310);
DISPLAY 0.680851 (-2760 5310);
PAINT MONO (-2760 5310);
FORCEPROP 0 LASTPIN (-2750 5250) $PN AE35
J 2
(-2760 5260);
DISPLAY 0.680851 (-2760 5260);
PAINT MONO (-2760 5260);
FORCEPROP 0 LASTPIN (-2750 5200) $PN AK13
J 2
(-2760 5210);
DISPLAY 0.680851 (-2760 5210);
PAINT MONO (-2760 5210);
FORCEPROP 0 LASTPIN (-2750 5150) $PN AK22
J 2
(-2760 5160);
DISPLAY 0.680851 (-2760 5160);
PAINT MONO (-2760 5160);
FORCEPROP 0 LASTPIN (-2750 5100) $PN AK32
J 2
(-2760 5110);
DISPLAY 0.680851 (-2760 5110);
PAINT MONO (-2760 5110);
FORCEPROP 0 LASTPIN (-2750 5050) $PN AK4
J 2
(-2760 5060);
DISPLAY 0.680851 (-2760 5060);
PAINT MONO (-2760 5060);
FORCEPROP 0 LASTPIN (-2750 5000) $PN AL2
J 2
(-2760 5010);
DISPLAY 0.680851 (-2760 5010);
PAINT MONO (-2760 5010);
FORCEPROP 0 LASTPIN (-2750 4950) $PN AL34
J 2
(-2760 4960);
DISPLAY 0.680851 (-2760 4960);
PAINT MONO (-2760 4960);
FORCEPROP 0 LASTPIN (-2750 4900) $PN AM1
J 2
(-2760 4910);
DISPLAY 0.680851 (-2760 4910);
PAINT MONO (-2760 4910);
FORCEPROP 0 LASTPIN (-2750 4850) $PN AM35
J 2
(-2760 4860);
DISPLAY 0.680851 (-2760 4860);
PAINT MONO (-2760 4860);
FORCEPROP 0 LASTPIN (-2750 4800) $PN AU13
J 2
(-2760 4810);
DISPLAY 0.680851 (-2760 4810);
PAINT MONO (-2760 4810);
FORCEPROP 0 LASTPIN (-2750 4750) $PN AU22
J 2
(-2760 4760);
DISPLAY 0.680851 (-2760 4760);
PAINT MONO (-2760 4760);
FORCEPROP 0 LASTPIN (-2750 4700) $PN AU32
J 2
(-2760 4710);
DISPLAY 0.680851 (-2760 4710);
PAINT MONO (-2760 4710);
FORCEPROP 0 LASTPIN (-2750 4650) $PN AU4
J 2
(-2760 4660);
DISPLAY 0.680851 (-2760 4660);
PAINT MONO (-2760 4660);
FORCEPROP 0 LASTPIN (-2750 4600) $PN AV2
J 2
(-2760 4610);
DISPLAY 0.680851 (-2760 4610);
PAINT MONO (-2760 4610);
FORCEPROP 0 LASTPIN (-2750 4550) $PN AV34
J 2
(-2760 4560);
DISPLAY 0.680851 (-2760 4560);
PAINT MONO (-2760 4560);
FORCEPROP 0 LASTPIN (-2750 4500) $PN AW1
J 2
(-2760 4510);
DISPLAY 0.680851 (-2760 4510);
PAINT MONO (-2760 4510);
FORCEPROP 0 LASTPIN (-2750 4450) $PN AW35
J 2
(-2760 4460);
DISPLAY 0.680851 (-2760 4460);
PAINT MONO (-2760 4460);
FORCEPROP 0 LASTPIN (-2750 4400) $PN B19
J 2
(-2760 4410);
DISPLAY 0.680851 (-2760 4410);
PAINT MONO (-2760 4410);
FORCEPROP 0 LASTPIN (-2750 4350) $PN BD13
J 2
(-2760 4360);
DISPLAY 0.680851 (-2760 4360);
PAINT MONO (-2760 4360);
FORCEPROP 0 LASTPIN (-2750 4300) $PN BD22
J 2
(-2760 4310);
DISPLAY 0.680851 (-2760 4310);
PAINT MONO (-2760 4310);
FORCEPROP 0 LASTPIN (-2750 4250) $PN BD32
J 2
(-2760 4260);
DISPLAY 0.680851 (-2760 4260);
PAINT MONO (-2760 4260);
FORCEPROP 0 LASTPIN (-2750 4200) $PN BD4
J 2
(-2760 4210);
DISPLAY 0.680851 (-2760 4210);
PAINT MONO (-2760 4210);
FORCEPROP 0 LASTPIN (-2750 4150) $PN BE2
J 2
(-2760 4160);
DISPLAY 0.680851 (-2760 4160);
PAINT MONO (-2760 4160);
FORCEPROP 0 LASTPIN (-2750 4100) $PN BE34
J 2
(-2760 4110);
DISPLAY 0.680851 (-2760 4110);
PAINT MONO (-2760 4110);
FORCEPROP 0 LASTPIN (-2750 4050) $PN BF1
J 2
(-2760 4060);
DISPLAY 0.680851 (-2760 4060);
PAINT MONO (-2760 4060);
FORCEPROP 0 LASTPIN (-2750 4000) $PN BF35
J 2
(-2760 4010);
DISPLAY 0.680851 (-2760 4010);
PAINT MONO (-2760 4010);
FORCEPROP 0 LASTPIN (-2750 3950) $PN BL13
J 2
(-2760 3960);
DISPLAY 0.680851 (-2760 3960);
PAINT MONO (-2760 3960);
FORCEPROP 0 LASTPIN (-2750 3900) $PN BL22
J 2
(-2760 3910);
DISPLAY 0.680851 (-2760 3910);
PAINT MONO (-2760 3910);
FORCEPROP 0 LASTPIN (-2750 3850) $PN BL32
J 2
(-2760 3860);
DISPLAY 0.680851 (-2760 3860);
PAINT MONO (-2760 3860);
FORCEPROP 0 LASTPIN (-2750 3800) $PN BL4
J 2
(-2760 3810);
DISPLAY 0.680851 (-2760 3810);
PAINT MONO (-2760 3810);
FORCEPROP 0 LASTPIN (-2750 3750) $PN BM2
J 2
(-2760 3760);
DISPLAY 0.680851 (-2760 3760);
PAINT MONO (-2760 3760);
FORCEPROP 0 LASTPIN (-2750 3700) $PN BM34
J 2
(-2760 3710);
DISPLAY 0.680851 (-2760 3710);
PAINT MONO (-2760 3710);
FORCEPROP 0 LASTPIN (-2750 3650) $PN BN1
J 2
(-2760 3660);
DISPLAY 0.680851 (-2760 3660);
PAINT MONO (-2760 3660);
FORCEPROP 0 LASTPIN (-2750 3600) $PN BN35
J 2
(-2760 3610);
DISPLAY 0.680851 (-2760 3610);
PAINT MONO (-2760 3610);
FORCEPROP 0 LASTPIN (-2750 3550) $PN BV13
J 2
(-2760 3560);
DISPLAY 0.680851 (-2760 3560);
PAINT MONO (-2760 3560);
FORCEPROP 0 LASTPIN (-2750 3500) $PN BV22
J 2
(-2760 3510);
DISPLAY 0.680851 (-2760 3510);
PAINT MONO (-2760 3510);
FORCEPROP 0 LASTPIN (-2750 3450) $PN BV32
J 2
(-2760 3460);
DISPLAY 0.680851 (-2760 3460);
PAINT MONO (-2760 3460);
FORCEPROP 0 LASTPIN (-2750 3400) $PN BV4
J 2
(-2760 3410);
DISPLAY 0.680851 (-2760 3410);
PAINT MONO (-2760 3410);
FORCEPROP 0 LASTPIN (-2750 3350) $PN BW2
J 2
(-2760 3360);
DISPLAY 0.680851 (-2760 3360);
PAINT MONO (-2760 3360);
FORCEPROP 0 LASTPIN (-2750 3300) $PN BW34
J 2
(-2760 3310);
DISPLAY 0.680851 (-2760 3310);
PAINT MONO (-2760 3310);
FORCEPROP 0 LASTPIN (-2750 3250) $PN BY1
J 2
(-2760 3260);
DISPLAY 0.680851 (-2760 3260);
PAINT MONO (-2760 3260);
FORCEPROP 0 LASTPIN (-2750 3200) $PN BY35
J 2
(-2760 3210);
DISPLAY 0.680851 (-2760 3210);
PAINT MONO (-2760 3210);
FORCEPROP 0 LASTPIN (-2750 3150) $PN CE13
J 2
(-2760 3160);
DISPLAY 0.680851 (-2760 3160);
PAINT MONO (-2760 3160);
FORCEPROP 0 LASTPIN (-2750 3100) $PN CE22
J 2
(-2760 3110);
DISPLAY 0.680851 (-2760 3110);
PAINT MONO (-2760 3110);
FORCEPROP 0 LASTPIN (-2750 3050) $PN CE32
J 2
(-2760 3060);
DISPLAY 0.680851 (-2760 3060);
PAINT MONO (-2760 3060);
FORCEPROP 0 LASTPIN (-2750 3000) $PN CE4
J 2
(-2760 3010);
DISPLAY 0.680851 (-2760 3010);
PAINT MONO (-2760 3010);
FORCEPROP 0 LASTPIN (-2750 2950) $PN CF2
J 2
(-2760 2960);
DISPLAY 0.680851 (-2760 2960);
PAINT MONO (-2760 2960);
FORCEPROP 0 LASTPIN (-2750 2900) $PN CF34
J 2
(-2760 2910);
DISPLAY 0.680851 (-2760 2910);
PAINT MONO (-2760 2910);
FORCEPROP 0 LASTPIN (-2750 2850) $PN CG1
J 2
(-2760 2860);
DISPLAY 0.680851 (-2760 2860);
PAINT MONO (-2760 2860);
FORCEPROP 0 LASTPIN (-2750 2800) $PN CG35
J 2
(-2760 2810);
DISPLAY 0.680851 (-2760 2810);
PAINT MONO (-2760 2810);
FORCEPROP 0 LASTPIN (-2750 2750) $PN CM13
J 2
(-2760 2760);
DISPLAY 0.680851 (-2760 2760);
PAINT MONO (-2760 2760);
FORCEPROP 0 LASTPIN (-2750 2700) $PN CM22
J 2
(-2760 2710);
DISPLAY 0.680851 (-2760 2710);
PAINT MONO (-2760 2710);
FORCEPROP 0 LASTPIN (-2750 2650) $PN CM32
J 2
(-2760 2660);
DISPLAY 0.680851 (-2760 2660);
PAINT MONO (-2760 2660);
FORCEPROP 0 LASTPIN (-2750 2600) $PN CM4
J 2
(-2760 2610);
DISPLAY 0.680851 (-2760 2610);
PAINT MONO (-2760 2610);
FORCEPROP 0 LASTPIN (-2750 2550) $PN CN2
J 2
(-2760 2560);
DISPLAY 0.680851 (-2760 2560);
PAINT MONO (-2760 2560);
FORCEPROP 0 LASTPIN (-2750 2500) $PN CN34
J 2
(-2760 2510);
DISPLAY 0.680851 (-2760 2510);
PAINT MONO (-2760 2510);
FORCEPROP 0 LASTPIN (-2750 2450) $PN CP1
J 2
(-2760 2460);
DISPLAY 0.680851 (-2760 2460);
PAINT MONO (-2760 2460);
FORCEPROP 0 LASTPIN (-2750 2400) $PN CP35
J 2
(-2760 2410);
DISPLAY 0.680851 (-2760 2410);
PAINT MONO (-2760 2410);
FORCEPROP 0 LASTPIN (-2750 2350) $PN CW13
J 2
(-2760 2360);
DISPLAY 0.680851 (-2760 2360);
PAINT MONO (-2760 2360);
FORCEPROP 0 LASTPIN (-2750 2300) $PN CW22
J 2
(-2760 2310);
DISPLAY 0.680851 (-2760 2310);
PAINT MONO (-2760 2310);
FORCEPROP 0 LASTPIN (-2750 2250) $PN CW32
J 2
(-2760 2260);
DISPLAY 0.680851 (-2760 2260);
PAINT MONO (-2760 2260);
FORCEPROP 0 LASTPIN (-2750 2200) $PN CW4
J 2
(-2760 2210);
DISPLAY 0.680851 (-2760 2210);
PAINT MONO (-2760 2210);
FORCEPROP 0 LASTPIN (-2750 2150) $PN CY2
J 2
(-2760 2160);
DISPLAY 0.680851 (-2760 2160);
PAINT MONO (-2760 2160);
FORCEPROP 0 LASTPIN (-2750 2100) $PN CY34
J 2
(-2760 2110);
DISPLAY 0.680851 (-2760 2110);
PAINT MONO (-2760 2110);
FORCEPROP 0 LASTPIN (-2750 2050) $PN DA1
J 2
(-2760 2060);
DISPLAY 0.680851 (-2760 2060);
PAINT MONO (-2760 2060);
FORCEPROP 0 LASTPIN (-2750 2000) $PN DA35
J 2
(-2760 2010);
DISPLAY 0.680851 (-2760 2010);
PAINT MONO (-2760 2010);
FORCEPROP 0 LASTPIN (-2750 1950) $PN DF13
J 2
(-2760 1960);
DISPLAY 0.680851 (-2760 1960);
PAINT MONO (-2760 1960);
FORCEPROP 0 LASTPIN (-2750 1900) $PN DF22
J 2
(-2760 1910);
DISPLAY 0.680851 (-2760 1910);
PAINT MONO (-2760 1910);
FORCEPROP 0 LASTPIN (-2750 1850) $PN DF32
J 2
(-2760 1860);
DISPLAY 0.680851 (-2760 1860);
PAINT MONO (-2760 1860);
FORCEPROP 0 LASTPIN (-2750 1800) $PN DF4
J 2
(-2760 1810);
DISPLAY 0.680851 (-2760 1810);
PAINT MONO (-2760 1810);
FORCEPROP 0 LASTPIN (-2750 1750) $PN DG2
J 2
(-2760 1760);
DISPLAY 0.680851 (-2760 1760);
PAINT MONO (-2760 1760);
FORCEPROP 0 LASTPIN (-2750 1700) $PN DG34
J 2
(-2760 1710);
DISPLAY 0.680851 (-2760 1710);
PAINT MONO (-2760 1710);
FORCEPROP 0 LASTPIN (-2750 1650) $PN DH1
J 2
(-2760 1660);
DISPLAY 0.680851 (-2760 1660);
PAINT MONO (-2760 1660);
FORCEPROP 0 LASTPIN (-2750 1600) $PN DH35
J 2
(-2760 1610);
DISPLAY 0.680851 (-2760 1610);
PAINT MONO (-2760 1610);
FORCEPROP 0 LASTPIN (-2750 1550) $PN DN13
J 2
(-2760 1560);
DISPLAY 0.680851 (-2760 1560);
PAINT MONO (-2760 1560);
FORCEPROP 0 LASTPIN (-1800 5600) $PN DN22
J 0
(-1790 5610);
DISPLAY 0.680851 (-1790 5610);
PAINT MONO (-1790 5610);
FORCEPROP 0 LASTPIN (-1800 5550) $PN DN32
J 0
(-1790 5560);
DISPLAY 0.680851 (-1790 5560);
PAINT MONO (-1790 5560);
FORCEPROP 0 LASTPIN (-1800 5500) $PN DN4
J 0
(-1790 5510);
DISPLAY 0.680851 (-1790 5510);
PAINT MONO (-1790 5510);
FORCEPROP 0 LASTPIN (-1800 5450) $PN DP2
J 0
(-1790 5460);
DISPLAY 0.680851 (-1790 5460);
PAINT MONO (-1790 5460);
FORCEPROP 0 LASTPIN (-1800 5400) $PN DP34
J 0
(-1790 5410);
DISPLAY 0.680851 (-1790 5410);
PAINT MONO (-1790 5410);
FORCEPROP 0 LASTPIN (-1800 5350) $PN DR1
J 0
(-1790 5360);
DISPLAY 0.680851 (-1790 5360);
PAINT MONO (-1790 5360);
FORCEPROP 0 LASTPIN (-1800 5300) $PN DR35
J 0
(-1790 5310);
DISPLAY 0.680851 (-1790 5310);
PAINT MONO (-1790 5310);
FORCEPROP 0 LASTPIN (-1800 5250) $PN DY13
J 0
(-1790 5260);
DISPLAY 0.680851 (-1790 5260);
PAINT MONO (-1790 5260);
FORCEPROP 0 LASTPIN (-1800 5200) $PN DY22
J 0
(-1790 5210);
DISPLAY 0.680851 (-1790 5210);
PAINT MONO (-1790 5210);
FORCEPROP 0 LASTPIN (-1800 5150) $PN DY32
J 0
(-1790 5160);
DISPLAY 0.680851 (-1790 5160);
PAINT MONO (-1790 5160);
FORCEPROP 0 LASTPIN (-1800 5100) $PN DY4
J 0
(-1790 5110);
DISPLAY 0.680851 (-1790 5110);
PAINT MONO (-1790 5110);
FORCEPROP 0 LASTPIN (-1800 5050) $PN E14
J 0
(-1790 5060);
DISPLAY 0.680851 (-1790 5060);
PAINT MONO (-1790 5060);
FORCEPROP 0 LASTPIN (-1800 5000) $PN E27
J 0
(-1790 5010);
DISPLAY 0.680851 (-1790 5010);
PAINT MONO (-1790 5010);
FORCEPROP 0 LASTPIN (-1800 4950) $PN E33
J 0
(-1790 4960);
DISPLAY 0.680851 (-1790 4960);
PAINT MONO (-1790 4960);
FORCEPROP 0 LASTPIN (-1800 4900) $PN EA2
J 0
(-1790 4910);
DISPLAY 0.680851 (-1790 4910);
PAINT MONO (-1790 4910);
FORCEPROP 0 LASTPIN (-1800 4850) $PN EA34
J 0
(-1790 4860);
DISPLAY 0.680851 (-1790 4860);
PAINT MONO (-1790 4860);
FORCEPROP 0 LASTPIN (-1800 4800) $PN EB1
J 0
(-1790 4810);
DISPLAY 0.680851 (-1790 4810);
PAINT MONO (-1790 4810);
FORCEPROP 0 LASTPIN (-1800 4750) $PN EB35
J 0
(-1790 4760);
DISPLAY 0.680851 (-1790 4760);
PAINT MONO (-1790 4760);
FORCEPROP 0 LASTPIN (-1800 4700) $PN EG13
J 0
(-1790 4710);
DISPLAY 0.680851 (-1790 4710);
PAINT MONO (-1790 4710);
FORCEPROP 0 LASTPIN (-1800 4650) $PN EG22
J 0
(-1790 4660);
DISPLAY 0.680851 (-1790 4660);
PAINT MONO (-1790 4660);
FORCEPROP 0 LASTPIN (-1800 4600) $PN EG32
J 0
(-1790 4610);
DISPLAY 0.680851 (-1790 4610);
PAINT MONO (-1790 4610);
FORCEPROP 0 LASTPIN (-1800 4550) $PN EG4
J 0
(-1790 4560);
DISPLAY 0.680851 (-1790 4560);
PAINT MONO (-1790 4560);
FORCEPROP 0 LASTPIN (-1800 4500) $PN EH2
J 0
(-1790 4510);
DISPLAY 0.680851 (-1790 4510);
PAINT MONO (-1790 4510);
FORCEPROP 0 LASTPIN (-1800 4450) $PN EH34
J 0
(-1790 4460);
DISPLAY 0.680851 (-1790 4460);
PAINT MONO (-1790 4460);
FORCEPROP 0 LASTPIN (-1800 4400) $PN EJ1
J 0
(-1790 4410);
DISPLAY 0.680851 (-1790 4410);
PAINT MONO (-1790 4410);
FORCEPROP 0 LASTPIN (-1800 4350) $PN EJ35
J 0
(-1790 4360);
DISPLAY 0.680851 (-1790 4360);
PAINT MONO (-1790 4360);
FORCEPROP 0 LASTPIN (-1800 4300) $PN EP13
J 0
(-1790 4310);
DISPLAY 0.680851 (-1790 4310);
PAINT MONO (-1790 4310);
FORCEPROP 0 LASTPIN (-1800 4250) $PN EP22
J 0
(-1790 4260);
DISPLAY 0.680851 (-1790 4260);
PAINT MONO (-1790 4260);
FORCEPROP 0 LASTPIN (-1800 4200) $PN EP32
J 0
(-1790 4210);
DISPLAY 0.680851 (-1790 4210);
PAINT MONO (-1790 4210);
FORCEPROP 0 LASTPIN (-1800 4150) $PN EP4
J 0
(-1790 4160);
DISPLAY 0.680851 (-1790 4160);
PAINT MONO (-1790 4160);
FORCEPROP 0 LASTPIN (-1800 4100) $PN ER2
J 0
(-1790 4110);
DISPLAY 0.680851 (-1790 4110);
PAINT MONO (-1790 4110);
FORCEPROP 0 LASTPIN (-1800 4050) $PN ER34
J 0
(-1790 4060);
DISPLAY 0.680851 (-1790 4060);
PAINT MONO (-1790 4060);
FORCEPROP 0 LASTPIN (-1800 4000) $PN ET1
J 0
(-1790 4010);
DISPLAY 0.680851 (-1790 4010);
PAINT MONO (-1790 4010);
FORCEPROP 0 LASTPIN (-1800 3950) $PN ET35
J 0
(-1790 3960);
DISPLAY 0.680851 (-1790 3960);
PAINT MONO (-1790 3960);
FORCEPROP 0 LASTPIN (-1800 3900) $PN FA15
J 0
(-1790 3910);
DISPLAY 0.680851 (-1790 3910);
PAINT MONO (-1790 3910);
FORCEPROP 0 LASTPIN (-1800 3850) $PN FA32
J 0
(-1790 3860);
DISPLAY 0.680851 (-1790 3860);
PAINT MONO (-1790 3860);
FORCEPROP 0 LASTPIN (-1800 3800) $PN FB2
J 0
(-1790 3810);
DISPLAY 0.680851 (-1790 3810);
PAINT MONO (-1790 3810);
FORCEPROP 0 LASTPIN (-1800 3750) $PN FB34
J 0
(-1790 3760);
DISPLAY 0.680851 (-1790 3760);
PAINT MONO (-1790 3760);
FORCEPROP 0 LASTPIN (-1800 3700) $PN FC19
J 0
(-1790 3710);
DISPLAY 0.680851 (-1790 3710);
PAINT MONO (-1790 3710);
FORCEPROP 0 LASTPIN (-1800 3650) $PN FC23
J 0
(-1790 3660);
DISPLAY 0.680851 (-1790 3660);
PAINT MONO (-1790 3660);
FORCEPROP 0 LASTPIN (-1800 3600) $PN FC25
J 0
(-1790 3610);
DISPLAY 0.680851 (-1790 3610);
PAINT MONO (-1790 3610);
FORCEPROP 0 LASTPIN (-1800 3550) $PN FC28
J 0
(-1790 3560);
DISPLAY 0.680851 (-1790 3560);
PAINT MONO (-1790 3560);
FORCEPROP 0 LASTPIN (-1800 3500) $PN FC3
J 0
(-1790 3510);
DISPLAY 0.680851 (-1790 3510);
PAINT MONO (-1790 3510);
FORCEPROP 0 LASTPIN (-1800 3450) $PN FC6
J 0
(-1790 3460);
DISPLAY 0.680851 (-1790 3460);
PAINT MONO (-1790 3460);
FORCEPROP 0 LASTPIN (-1800 3400) $PN FC9
J 0
(-1790 3410);
DISPLAY 0.680851 (-1790 3410);
PAINT MONO (-1790 3410);
FORCEPROP 0 LASTPIN (-1800 3350) $PN FD1
J 0
(-1790 3360);
DISPLAY 0.680851 (-1790 3360);
PAINT MONO (-1790 3360);
FORCEPROP 0 LASTPIN (-1800 3300) $PN FD35
J 0
(-1790 3310);
DISPLAY 0.680851 (-1790 3310);
PAINT MONO (-1790 3310);
FORCEPROP 0 LASTPIN (-1800 3250) $PN FF14
J 0
(-1790 3260);
DISPLAY 0.680851 (-1790 3260);
PAINT MONO (-1790 3260);
FORCEPROP 0 LASTPIN (-1800 3200) $PN FF21
J 0
(-1790 3210);
DISPLAY 0.680851 (-1790 3210);
PAINT MONO (-1790 3210);
FORCEPROP 0 LASTPIN (-1800 3150) $PN FJ12
J 0
(-1790 3160);
DISPLAY 0.680851 (-1790 3160);
PAINT MONO (-1790 3160);
FORCEPROP 0 LASTPIN (-1800 3100) $PN FJ19
J 0
(-1790 3110);
DISPLAY 0.680851 (-1790 3110);
PAINT MONO (-1790 3110);
FORCEPROP 0 LASTPIN (-1800 3050) $PN H12
J 0
(-1790 3060);
DISPLAY 0.680851 (-1790 3060);
PAINT MONO (-1790 3060);
FORCEPROP 0 LASTPIN (-1800 3000) $PN H16
J 0
(-1790 3010);
DISPLAY 0.680851 (-1790 3010);
PAINT MONO (-1790 3010);
FORCEPROP 0 LASTPIN (-1800 2950) $PN H19
J 0
(-1790 2960);
DISPLAY 0.680851 (-1790 2960);
PAINT MONO (-1790 2960);
FORCEPROP 0 LASTPIN (-1800 2900) $PN H31
J 0
(-1790 2910);
DISPLAY 0.680851 (-1790 2910);
PAINT MONO (-1790 2910);
FORCEPROP 0 LASTPIN (-1800 2850) $PN J22
J 0
(-1790 2860);
DISPLAY 0.680851 (-1790 2860);
PAINT MONO (-1790 2860);
FORCEPROP 0 LASTPIN (-1800 2800) $PN J4
J 0
(-1790 2810);
DISPLAY 0.680851 (-1790 2810);
PAINT MONO (-1790 2810);
FORCEPROP 0 LASTPIN (-1800 2750) $PN K2
J 0
(-1790 2760);
DISPLAY 0.680851 (-1790 2760);
PAINT MONO (-1790 2760);
FORCEPROP 0 LASTPIN (-1800 2700) $PN K34
J 0
(-1790 2710);
DISPLAY 0.680851 (-1790 2710);
PAINT MONO (-1790 2710);
FORCEPROP 0 LASTPIN (-1800 2650) $PN L1
J 0
(-1790 2660);
DISPLAY 0.680851 (-1790 2660);
PAINT MONO (-1790 2660);
FORCEPROP 0 LASTPIN (-1800 2600) $PN L35
J 0
(-1790 2610);
DISPLAY 0.680851 (-1790 2610);
PAINT MONO (-1790 2610);
FORCEPROP 0 LASTPIN (-1800 2550) $PN T13
J 0
(-1790 2560);
DISPLAY 0.680851 (-1790 2560);
PAINT MONO (-1790 2560);
FORCEPROP 0 LASTPIN (-1800 2500) $PN T22
J 0
(-1790 2510);
DISPLAY 0.680851 (-1790 2510);
PAINT MONO (-1790 2510);
FORCEPROP 0 LASTPIN (-1800 2450) $PN T32
J 0
(-1790 2460);
DISPLAY 0.680851 (-1790 2460);
PAINT MONO (-1790 2460);
FORCEPROP 0 LASTPIN (-1800 2400) $PN T4
J 0
(-1790 2410);
DISPLAY 0.680851 (-1790 2410);
PAINT MONO (-1790 2410);
FORCEPROP 0 LASTPIN (-1800 2350) $PN U2
J 0
(-1790 2360);
DISPLAY 0.680851 (-1790 2360);
PAINT MONO (-1790 2360);
FORCEPROP 0 LASTPIN (-1800 2300) $PN U34
J 0
(-1790 2310);
DISPLAY 0.680851 (-1790 2310);
PAINT MONO (-1790 2310);
FORCEPROP 0 LASTPIN (-1800 2250) $PN V1
J 0
(-1790 2260);
DISPLAY 0.680851 (-1790 2260);
PAINT MONO (-1790 2260);
FORCEPROP 0 LASTPIN (-1800 2200) $PN V35
J 0
(-1790 2210);
DISPLAY 0.680851 (-1790 2210);
PAINT MONO (-1790 2210);
FORCEPROP 0 LASTPIN (-1800 2100) $PN A1
J 0
(-1790 2110);
DISPLAY 0.680851 (-1790 2110);
PAINT MONO (-1790 2110);
FORCEPROP 0 LASTPIN (-1800 2050) $PN A35
J 0
(-1790 2060);
DISPLAY 0.680851 (-1790 2060);
PAINT MONO (-1790 2060);
FORCEPROP 0 LASTPIN (-1800 2000) $PN C2
J 0
(-1790 2010);
DISPLAY 0.680851 (-1790 2010);
PAINT MONO (-1790 2010);
FORCEPROP 0 LASTPIN (-1800 1950) $PN C34
J 0
(-1790 1960);
DISPLAY 0.680851 (-1790 1960);
PAINT MONO (-1790 1960);
FORCEPROP 0 LASTPIN (-1800 1900) $PN D1
J 0
(-1790 1910);
DISPLAY 0.680851 (-1790 1910);
PAINT MONO (-1790 1910);
FORCEPROP 0 LASTPIN (-1800 1850) $PN D35
J 0
(-1790 1860);
DISPLAY 0.680851 (-1790 1860);
PAINT MONO (-1790 1860);
FORCEPROP 0 LASTPIN (-1800 1800) $PN FE2
J 0
(-1790 1810);
DISPLAY 0.680851 (-1790 1810);
PAINT MONO (-1790 1810);
FORCEPROP 0 LASTPIN (-1800 1750) $PN FE34
J 0
(-1790 1760);
DISPLAY 0.680851 (-1790 1760);
PAINT MONO (-1790 1760);
FORCEPROP 0 LASTPIN (-1800 1700) $PN FG1
J 0
(-1790 1710);
DISPLAY 0.680851 (-1790 1710);
PAINT MONO (-1790 1710);
FORCEPROP 0 LASTPIN (-1800 1650) $PN FG35
J 0
(-1790 1660);
DISPLAY 0.680851 (-1790 1660);
PAINT MONO (-1790 1660);
FORCEPROP 0 LASTPIN (-1800 1600) $PN FH2
J 0
(-1790 1610);
DISPLAY 0.680851 (-1790 1610);
PAINT MONO (-1790 1610);
FORCEPROP 0 LASTPIN (-1800 1550) $PN FH34
J 0
(-1790 1560);
DISPLAY 0.680851 (-1790 1560);
PAINT MONO (-1790 1560);
FORCEPROP 2 LAST PART_TYPE SMLF
J 0
(-2600 6025);
DISPLAY 0.680851 (-2600 6025);
FORCEPROP 2 LAST VALUE PT5161LRS
J 0
(-2600 5975);
DISPLAY 0.680851 (-2600 5975);
FORCEPROP 1 LAST MATERIAL IC
J 0
(-2600 5775);
DISPLAY 0.723404 (-2600 5775);
PAINT GREEN (-2600 5775);
FORCEPROP 1 LAST NEEDS_NO_SIZE TRUE
J 0
(-2250 3600);
DISPLAY 0.723404 (-2250 3600);
PAINT GREEN (-2250 3600);
DISPLAY INVISIBLE (-2250 3600);
FORCEPROP 1 LAST CDS_LMAN_SYM_OUTLINE -350,2150,300,-2150
J 0
(-2250 3600);
DISPLAY 0.468085 (-2250 3600);
PAINT GREEN (-2250 3600);
DISPLAY INVISIBLE (-2250 3600);
FORCEPROP 2 LAST CDS_LIB pure_quanta
J 0
(-2250 3600);
DISPLAY INVISIBLE (-2250 3600);
FORCEPROP 1 LAST PATH I19
J 0
(-2250 3600);
DISPLAY 0.723404 (-2250 3600);
PAINT GREEN (-2250 3600);
DISPLAY INVISIBLE (-2250 3600);
FORCEPROP 1 LAST PART_NUMBER AJ051610U03
J 0
(-2600 5850);
DISPLAY 0.723404 (-2600 5850);
PAINT GREEN (-2600 5850);
DISPLAY INVISIBLE (-2600 5850);
FORCEADD Q_RES..2
(-7475 3375);
FORCEPROP 1 LAST LOCATION R6731
J 0
(-7430 3500);
DISPLAY 0.978723 (-7430 3500);
PAINT WHITE (-7430 3500);
FORCEPROP 0 LAST $SEC 1
J 0
(-7425 3550);
DISPLAY 0.680851 (-7425 3550);
PAINT MONO (-7425 3550);
DISPLAY INVISIBLE (-7425 3550);
FORCEPROP 0 LAST CDS_SEC 1
J 0
(-7425 3550);
DISPLAY 0.680851 (-7425 3550);
DISPLAY INVISIBLE (-7425 3550);
FORCEPROP 1 LASTPIN (-7475 3475) $PN 1
J 0
(-7470 3437);
DISPLAY 0.787234 (-7470 3437);
PAINT MONO (-7470 3437);
FORCEPROP 1 LASTPIN (-7475 3275) $PN 2
J 0
(-7470 3285);
DISPLAY 0.787234 (-7470 3285);
PAINT MONO (-7470 3285);
FORCEPROP 1 LAST VALUE 200
J 0
(-7430 3450);
DISPLAY 0.978723 (-7430 3450);
FORCEPROP 1 LAST WATTAGE 1/20W
J 0
(-7435 3350);
DISPLAY 0.978723 (-7435 3350);
FORCEPROP 1 LAST TOLERANCE 1%
J 0
(-7430 3400);
DISPLAY 0.978723 (-7430 3400);
FORCEPROP 1 LAST MATERIAL CHIP
J 0
(-7435 3300);
DISPLAY 0.978723 (-7435 3300);
FORCEPROP 1 LAST PACK_TYPE 0201LF
J 0
(-7435 3200);
DISPLAY 0.978723 (-7435 3200);
FORCEPROP 2 LAST CDS_LIB pure_quanta
J 0
(-7475 3375);
DISPLAY INVISIBLE (-7475 3375);
FORCEPROP 1 LAST PATH I20
J 0
(-7425 3550);
DISPLAY 0.978723 (-7425 3550);
PAINT WHITE (-7425 3550);
DISPLAY INVISIBLE (-7425 3550);
FORCEPROP 1 LAST PART_NUMBER CS12001FE12
J 0
(-7435 3250);
DISPLAY 0.978723 (-7435 3250);
DISPLAY INVISIBLE (-7435 3250);
FORCEADD Q_RES..2
(-8500 3925);
FORCEPROP 1 LAST LOCATION R6730
J 0
(-8455 4050);
DISPLAY 0.787234 (-8455 4050);
PAINT SKYBLUE (-8455 4050);
FORCEPROP 0 LAST $SEC 1
J 0
(-8450 4100);
DISPLAY 0.680851 (-8450 4100);
PAINT MONO (-8450 4100);
DISPLAY INVISIBLE (-8450 4100);
FORCEPROP 0 LAST CDS_SEC 1
J 0
(-8450 4100);
DISPLAY 0.680851 (-8450 4100);
DISPLAY INVISIBLE (-8450 4100);
FORCEPROP 1 LASTPIN (-8500 4025) $PN 1
J 0
(-8495 3987);
DISPLAY 0.787234 (-8495 3987);
PAINT MONO (-8495 3987);
FORCEPROP 1 LASTPIN (-8500 3825) $PN 2
J 0
(-8495 3835);
DISPLAY 0.787234 (-8495 3835);
PAINT MONO (-8495 3835);
FORCEPROP 1 LAST VALUE 1K
J 0
(-8455 4000);
DISPLAY 0.787234 (-8455 4000);
FORCEPROP 1 LAST TOLERANCE 1%
J 0
(-8455 3950);
DISPLAY 0.787234 (-8455 3950);
FORCEPROP 1 LAST PACK_TYPE 0201LF
J 0
(-8460 3750);
DISPLAY 0.787234 (-8460 3750);
FORCEPROP 1 LAST MATERIAL EMPTY
J 0
(-8460 3850);
DISPLAY 0.787234 (-8460 3850);
PAINT RED (-8460 3850);
FORCEPROP 1 LAST WATTAGE 1/20W
J 0
(-8460 3900);
DISPLAY 0.787234 (-8460 3900);
FORCEPROP 2 LAST CDS_LIB pure_quanta
J 0
(-8500 3925);
DISPLAY INVISIBLE (-8500 3925);
FORCEPROP 1 LAST PATH I21
J 0
(-8450 4100);
DISPLAY 0.978723 (-8450 4100);
PAINT WHITE (-8450 4100);
DISPLAY INVISIBLE (-8450 4100);
FORCEPROP 1 LAST PART_NUMBER CS21001FE07
J 0
(-8460 3800);
DISPLAY 0.978723 (-8460 3800);
DISPLAY INVISIBLE (-8460 3800);
FORCEADD UNIVERSAL_GND..1
(-7475 3125);
FORCEPROP 3 LASTPIN (-7475 3175) SIG_NAME GND\g
J 0
(-7465 3185);
DISPLAY 0.659574 (-7465 3185);
PAINT MONO (-7465 3185);
DISPLAY INVISIBLE (-7465 3185);
FORCEPROP 2 LAST CDS_LIB pure_quanta_power
J 0
(-7475 3125);
DISPLAY INVISIBLE (-7475 3125);
FORCEPROP 1 LAST HDL_POWER GND
J 1
(-7450 3050);
DISPLAY 0.872340 (-7450 3050);
PAINT GREEN (-7450 3050);
DISPLAY INVISIBLE (-7450 3050);
FORCEPROP 1 LAST PATH I3
J 0
(-7400 3125);
DISPLAY 0.872340 (-7400 3125);
PAINT AQUA (-7400 3125);
DISPLAY INVISIBLE (-7400 3125);
FORCEADD PT5161LRS..4
(-6325 4175);
FORCEPROP 1 LAST LOCATION U6015
J 0
(-6775 5100);
DISPLAY 0.723404 (-6775 5100);
PAINT GREEN (-6775 5100);
FORCEPROP 0 LAST $SEC 4
J 0
(-6775 5250);
DISPLAY 0.680851 (-6775 5250);
PAINT MONO (-6775 5250);
DISPLAY INVISIBLE (-6775 5250);
FORCEPROP 0 LAST CDS_SEC 4
J 0
(-6775 5250);
DISPLAY 0.680851 (-6775 5250);
DISPLAY INVISIBLE (-6775 5250);
FORCEPROP 0 LASTPIN (-6925 4775) $PN BV20
J 2
(-6935 4785);
DISPLAY 0.680851 (-6935 4785);
PAINT MONO (-6935 4785);
FORCEPROP 0 LASTPIN (-6925 4725) $PN CE17
J 2
(-6935 4735);
DISPLAY 0.680851 (-6935 4735);
PAINT MONO (-6935 4735);
FORCEPROP 0 LASTPIN (-6925 4675) $PN CE20
J 2
(-6935 4685);
DISPLAY 0.680851 (-6935 4685);
PAINT MONO (-6935 4685);
FORCEPROP 0 LASTPIN (-6925 4625) $PN CM17
J 2
(-6935 4635);
DISPLAY 0.680851 (-6935 4635);
PAINT MONO (-6935 4635);
FORCEPROP 0 LASTPIN (-6925 4575) $PN CM20
J 2
(-6935 4585);
DISPLAY 0.680851 (-6935 4585);
PAINT MONO (-6935 4585);
FORCEPROP 0 LASTPIN (-6925 4125) $PN BV17
J 2
(-6935 4135);
DISPLAY 0.680851 (-6935 4135);
PAINT MONO (-6935 4135);
FORCEPROP 0 LASTPIN (-5775 4775) $PN AC17
J 0
(-5765 4785);
DISPLAY 0.680851 (-5765 4785);
PAINT MONO (-5765 4785);
FORCEPROP 0 LASTPIN (-5775 4725) $PN AC20
J 0
(-5765 4735);
DISPLAY 0.680851 (-5765 4735);
PAINT MONO (-5765 4735);
FORCEPROP 0 LASTPIN (-5775 4675) $PN AK17
J 0
(-5765 4685);
DISPLAY 0.680851 (-5765 4685);
PAINT MONO (-5765 4685);
FORCEPROP 0 LASTPIN (-5775 4625) $PN AK20
J 0
(-5765 4635);
DISPLAY 0.680851 (-5765 4635);
PAINT MONO (-5765 4635);
FORCEPROP 0 LASTPIN (-5775 4575) $PN AU17
J 0
(-5765 4585);
DISPLAY 0.680851 (-5765 4585);
PAINT MONO (-5765 4585);
FORCEPROP 0 LASTPIN (-5775 4525) $PN AU20
J 0
(-5765 4535);
DISPLAY 0.680851 (-5765 4535);
PAINT MONO (-5765 4535);
FORCEPROP 0 LASTPIN (-5775 4475) $PN BD17
J 0
(-5765 4485);
DISPLAY 0.680851 (-5765 4485);
PAINT MONO (-5765 4485);
FORCEPROP 0 LASTPIN (-5775 4425) $PN BD20
J 0
(-5765 4435);
DISPLAY 0.680851 (-5765 4435);
PAINT MONO (-5765 4435);
FORCEPROP 0 LASTPIN (-5775 4375) $PN DF17
J 0
(-5765 4385);
DISPLAY 0.680851 (-5765 4385);
PAINT MONO (-5765 4385);
FORCEPROP 0 LASTPIN (-5775 4325) $PN DF20
J 0
(-5765 4335);
DISPLAY 0.680851 (-5765 4335);
PAINT MONO (-5765 4335);
FORCEPROP 0 LASTPIN (-5775 4275) $PN DN17
J 0
(-5765 4285);
DISPLAY 0.680851 (-5765 4285);
PAINT MONO (-5765 4285);
FORCEPROP 0 LASTPIN (-5775 4225) $PN DN20
J 0
(-5765 4235);
DISPLAY 0.680851 (-5765 4235);
PAINT MONO (-5765 4235);
FORCEPROP 0 LASTPIN (-5775 4175) $PN DY17
J 0
(-5765 4185);
DISPLAY 0.680851 (-5765 4185);
PAINT MONO (-5765 4185);
FORCEPROP 0 LASTPIN (-5775 4125) $PN DY20
J 0
(-5765 4135);
DISPLAY 0.680851 (-5765 4135);
PAINT MONO (-5765 4135);
FORCEPROP 0 LASTPIN (-5775 4075) $PN EG17
J 0
(-5765 4085);
DISPLAY 0.680851 (-5765 4085);
PAINT MONO (-5765 4085);
FORCEPROP 0 LASTPIN (-5775 4025) $PN EG20
J 0
(-5765 4035);
DISPLAY 0.680851 (-5765 4035);
PAINT MONO (-5765 4035);
FORCEPROP 0 LASTPIN (-5775 3975) $PN EP17
J 0
(-5765 3985);
DISPLAY 0.680851 (-5765 3985);
PAINT MONO (-5765 3985);
FORCEPROP 0 LASTPIN (-5775 3925) $PN EP20
J 0
(-5765 3935);
DISPLAY 0.680851 (-5765 3935);
PAINT MONO (-5765 3935);
FORCEPROP 0 LASTPIN (-5775 3875) $PN T17
J 0
(-5765 3885);
DISPLAY 0.680851 (-5765 3885);
PAINT MONO (-5765 3885);
FORCEPROP 0 LASTPIN (-5775 3825) $PN T20
J 0
(-5765 3835);
DISPLAY 0.680851 (-5765 3835);
PAINT MONO (-5765 3835);
FORCEPROP 0 LASTPIN (-5775 3675) $PN BL17
J 0
(-5765 3685);
DISPLAY 0.680851 (-5765 3685);
PAINT MONO (-5765 3685);
FORCEPROP 0 LASTPIN (-5775 3625) $PN BL20
J 0
(-5765 3635);
DISPLAY 0.680851 (-5765 3635);
PAINT MONO (-5765 3635);
FORCEPROP 0 LASTPIN (-5775 3575) $PN CW17
J 0
(-5765 3585);
DISPLAY 0.680851 (-5765 3585);
PAINT MONO (-5765 3585);
FORCEPROP 0 LASTPIN (-5775 3525) $PN CW20
J 0
(-5765 3535);
DISPLAY 0.680851 (-5765 3535);
PAINT MONO (-5765 3535);
FORCEPROP 0 LASTPIN (-6925 3675) $PN G1
J 2
(-6935 3685);
DISPLAY 0.680851 (-6935 3685);
PAINT MONO (-6935 3685);
FORCEPROP 2 LAST PART_TYPE SMLF
J 0
(-6775 5200);
DISPLAY 0.680851 (-6775 5200);
FORCEPROP 2 LAST VALUE PT5161LRS
J 0
(-6775 5150);
DISPLAY 0.680851 (-6775 5150);
FORCEPROP 1 LAST MATERIAL IC
J 0
(-6775 4950);
DISPLAY 0.723404 (-6775 4950);
PAINT GREEN (-6775 4950);
FORCEPROP 1 LAST NEEDS_NO_SIZE TRUE
J 0
(-6325 4175);
DISPLAY 0.723404 (-6325 4175);
PAINT GREEN (-6325 4175);
DISPLAY INVISIBLE (-6325 4175);
FORCEPROP 1 LAST CDS_LMAN_SYM_OUTLINE -450,750,400,-750
J 0
(-6325 4175);
DISPLAY 0.468085 (-6325 4175);
PAINT GREEN (-6325 4175);
DISPLAY INVISIBLE (-6325 4175);
FORCEPROP 2 LAST CDS_LIB pure_quanta
J 0
(-6325 4175);
DISPLAY INVISIBLE (-6325 4175);
FORCEPROP 1 LAST PATH I5
J 0
(-6325 4175);
DISPLAY 0.723404 (-6325 4175);
PAINT GREEN (-6325 4175);
DISPLAY INVISIBLE (-6325 4175);
FORCEPROP 1 LAST PART_NUMBER AJ051610U03
J 0
(-6775 5025);
DISPLAY 0.723404 (-6775 5025);
PAINT GREEN (-6775 5025);
DISPLAY INVISIBLE (-6775 5025);
FORCEADD P1V0..1
(-8500 4150);
FORCEPROP 3 LASTPIN (-8500 4100) SIG_NAME P1V8_CPU1_RT_1D\g
J 0
(-8490 4110);
DISPLAY 0.659574 (-8490 4110);
PAINT MONO (-8490 4110);
DISPLAY INVISIBLE (-8490 4110);
FORCEPROP 1 LAST HDL_POWER P1V8_CPU1_RT_1D
J 1
(-8500 4200);
DISPLAY 0.489362 (-8500 4200);
PAINT SKYBLUE (-8500 4200);
FORCEPROP 2 LAST CDS_LIB pure_quanta_power
J 0
(-8500 4150);
DISPLAY INVISIBLE (-8500 4150);
FORCEPROP 1 LAST PATH I7
J 0
(-8450 4175);
DISPLAY 0.872340 (-8450 4175);
PAINT AQUA (-8450 4175);
DISPLAY INVISIBLE (-8450 4175);
FORCEADD P1V0..1
(-8175 4425);
FORCEPROP 3 LASTPIN (-8175 4375) SIG_NAME P1V8_CPU1_RT1_1A_1D\g
J 0
(-8165 4385);
DISPLAY 0.659574 (-8165 4385);
PAINT MONO (-8165 4385);
DISPLAY INVISIBLE (-8165 4385);
FORCEPROP 1 LAST HDL_POWER P1V8_CPU1_RT1_1A_1D
J 1
(-8175 4475);
DISPLAY 0.489362 (-8175 4475);
PAINT SKYBLUE (-8175 4475);
FORCEPROP 2 LAST CDS_LIB pure_quanta_power
J 0
(-8175 4425);
DISPLAY INVISIBLE (-8175 4425);
FORCEPROP 1 LAST PATH I8
J 0
(-8125 4450);
DISPLAY 0.872340 (-8125 4450);
PAINT AQUA (-8125 4450);
DISPLAY INVISIBLE (-8125 4450);
FORCEADD P1V0..1
(-7600 4875);
FORCEPROP 3 LASTPIN (-7600 4825) SIG_NAME P1V8_CPU1_RT1_1A\g
J 0
(-7590 4835);
DISPLAY 0.659574 (-7590 4835);
PAINT MONO (-7590 4835);
DISPLAY INVISIBLE (-7590 4835);
FORCEPROP 1 LAST HDL_POWER P1V8_CPU1_RT1_1A
J 1
(-7600 4925);
DISPLAY 0.489362 (-7600 4925);
PAINT SKYBLUE (-7600 4925);
FORCEPROP 2 LAST CDS_LIB pure_quanta_power
J 0
(-7600 4875);
DISPLAY INVISIBLE (-7600 4875);
FORCEPROP 1 LAST PATH I9
J 0
(-7550 4900);
DISPLAY 0.872340 (-7550 4900);
PAINT AQUA (-7550 4900);
DISPLAY INVISIBLE (-7550 4900);
FORCEADD QUANTA_TITLE_BLOCK_C..1
(0 0);
FORCEPROP 0 LAST CDS_CON_LAST_MODIFIED Thu Sep 14 16:13:04 2023
J 0
(-1885 15);
DISPLAY INVISIBLE (-1885 15);
FORCEPROP 1 LAST CUSTOM_TXT_CDS <CON_LAST_MODIFIED>
J 0
(-1885 15);
DISPLAY 0.978723 (-1885 15);
FORCEPROP 2 LAST CUSTOM_TXT_CDS <XR_PAGE_TITLE>
J 0
(-7890 5250);
DISPLAY 0.638298 (-7890 5250);
PAINT PINK (-7890 5250);
DISPLAY INVISIBLE (-7890 5250);
FORCEPROP 1 LAST CUSTOM_TXT_CDS <NAME_2>
J 0
(-3175 50);
FORCEPROP 1 LAST CUSTOM_TXT_CDS <NAME_1>
J 0
(-3175 175);
FORCEPROP 1 LAST CUSTOM_TXT_CDS <Q_NUMBER>
J 0
(-1403 103);
DISPLAY 1.212766 (-1403 103);
FORCEPROP 1 LAST CUSTOM_TXT_CDS <Q_PROJ>
J 0
(-2382 102);
DISPLAY 1.212766 (-2382 102);
FORCEPROP 1 LAST CUSTOM_TXT_CDS <Q_REV>
J 0
(-184 103);
DISPLAY 1.212766 (-184 103);
FORCEPROP 1 LAST CUSTOM_TXT_CDS <CON_PAGE_NUM> OF <CON_TOTAL_PAGES>
J 0
(-446 18);
DISPLAY 0.978723 (-446 18);
FORCEPROP 1 LAST Q_TITLE RETIMER_CPU1_P1 POWER(6)
J 0
(-9366 26);
DISPLAY 2.446809 (-9366 26);
PAINT GREEN (-9366 26);
FORCEPROP 2 LAST CDS_LIB pure_quanta
J 0
(0 0);
DISPLAY INVISIBLE (0 0);
FORCEPROP 1 LAST CDS_LMAN_SYM_OUTLINE -9475,6775,100,-125
J 0
(0 0);
DISPLAY 0.468085 (0 0);
PAINT GREEN (0 0);
DISPLAY INVISIBLE (0 0);
FORCEPROP 2 LAST PAGE_BORDER TRUE
J 0
(-7890 5250);
DISPLAY 0.638298 (-7890 5250);
PAINT PINK (-7890 5250);
DISPLAY INVISIBLE (-7890 5250);
FORCEPROP 2 LAST CDS_XR_PAGE_TITLE CR-333 : @T6G_MB_LIB.T6G(SCH_1):PAGE333
J 0
(-7890 5250);
DISPLAY 0.638298 (-7890 5250);
PAINT PINK (-7890 5250);
DISPLAY INVISIBLE (-7890 5250);
FORCEPROP 1 LAST Q_DEPT BU9
J 1
(-3763 49);
DISPLAY 1.957447 (-3763 49);
PAINT GREEN (-3763 49);
DISPLAY INVISIBLE (-3763 49);
FORCEPROP 1 LAST COMMENT_BODY TRUE
J 0
(12 -13);
DISPLAY 0.978723 (12 -13);
PAINT GREEN (12 -13);
DISPLAY INVISIBLE (12 -13);
FORCEADD DNS..2
(-8425 3925);
PAINT RED (-8425 3925);
FORCEPROP 2 LAST CDS_LIB mstr_misc
J 0
(-8425 3925);
DISPLAY INVISIBLE (-8425 3925);
FORCEPROP 1 LAST COMMENT_BODY TRUE
J 0
(-8425 3925);
DISPLAY INVISIBLE (-8425 3925);
WIRE 16 -1 (-1275 1175)(-1275 1025);
WIRE 16 -1 (-1125 1725)(-1125 1575);
WIRE 16 -1 (-7475 3275)(-7475 3175);
WIRE 16 -1 (-8500 4100)(-8500 4025);
WIRE 16 -1 (-6925 3675)(-7475 3675);
WIRE 16 -1 (-7475 3675)(-7475 3475);
WIRE 16 -1 (-7475 3675)(-8500 3675);
FORCEPROP 2 LAST SIG_NAME RT_CPU1_P1_VQPS
J 0
(-7685 3685);
DISPLAY 0.680851 (-7685 3685);
PAINT SKYBLUE (-7685 3685);
FORCEPROP 2 LASTPROP $XRERR UNIQUE?
J 0
(-7925 3685);
DISPLAY 0.638298 (-7925 3685);
PAINT MONO (-7925 3685);
DISPLAY INVISIBLE (-7925 3685);
WIRE 16 -1 (-8500 3825)(-8500 3675);
WIRE 16 -1 (-6925 4775)(-7350 4775);
WIRE 16 -1 (-7350 4775)(-7350 4725);
WIRE 16 -1 (-7350 4775)(-7600 4775);
WIRE 16 -1 (-7600 4775)(-7600 4825);
WIRE 16 -1 (-6925 4725)(-7350 4725);
WIRE 16 -1 (-7350 4725)(-7350 4675);
WIRE 16 -1 (-6925 4675)(-7350 4675);
WIRE 16 -1 (-7350 4675)(-7350 4625);
WIRE 16 -1 (-6925 4625)(-7350 4625);
WIRE 16 -1 (-7350 4625)(-7350 4575);
WIRE 16 -1 (-7350 4575)(-6925 4575);
WIRE 16 -1 (-6925 4125)(-8175 4125);
WIRE 16 -1 (-8175 4375)(-8175 4125);
WIRE 16 -1 (-2750 5600)(-2950 5600);
WIRE 16 -1 (-2950 5600)(-2950 5550);
WIRE 16 -1 (-2750 5550)(-2950 5550);
WIRE 16 -1 (-2950 5550)(-2950 5500);
WIRE 16 -1 (-2750 5500)(-2950 5500);
WIRE 16 -1 (-2950 5500)(-2950 5450);
WIRE 16 -1 (-2750 5450)(-2950 5450);
WIRE 16 -1 (-2950 5450)(-2950 5400);
WIRE 16 -1 (-2750 5400)(-2950 5400);
WIRE 16 -1 (-2950 5400)(-2950 5350);
WIRE 16 -1 (-2750 5350)(-2950 5350);
WIRE 16 -1 (-2950 5350)(-2950 5300);
WIRE 16 -1 (-2750 5300)(-2950 5300);
WIRE 16 -1 (-2950 5300)(-2950 5250);
WIRE 16 -1 (-2750 5250)(-2950 5250);
WIRE 16 -1 (-2950 5250)(-2950 5200);
WIRE 16 -1 (-2750 5200)(-2950 5200);
WIRE 16 -1 (-2950 5200)(-2950 5150);
WIRE 16 -1 (-2750 5150)(-2950 5150);
WIRE 16 -1 (-2950 5150)(-2950 5100);
WIRE 16 -1 (-2750 5100)(-2950 5100);
WIRE 16 -1 (-2950 5100)(-2950 5050);
WIRE 16 -1 (-2750 5050)(-2950 5050);
WIRE 16 -1 (-2950 5050)(-2950 5000);
WIRE 16 -1 (-2750 5000)(-2950 5000);
WIRE 16 -1 (-2950 5000)(-2950 4950);
WIRE 16 -1 (-2750 4950)(-2950 4950);
WIRE 16 -1 (-2950 4950)(-2950 4900);
WIRE 16 -1 (-2750 4900)(-2950 4900);
WIRE 16 -1 (-2950 4900)(-2950 4850);
WIRE 16 -1 (-2750 4850)(-2950 4850);
WIRE 16 -1 (-2950 4850)(-2950 4800);
WIRE 16 -1 (-2750 4800)(-2950 4800);
WIRE 16 -1 (-2950 4800)(-2950 4750);
WIRE 16 -1 (-2750 4750)(-2950 4750);
WIRE 16 -1 (-2950 4750)(-2950 4700);
WIRE 16 -1 (-2750 4700)(-2950 4700);
WIRE 16 -1 (-2950 4700)(-2950 4650);
WIRE 16 -1 (-2750 4650)(-2950 4650);
WIRE 16 -1 (-2950 4650)(-2950 4600);
WIRE 16 -1 (-2750 4600)(-2950 4600);
WIRE 16 -1 (-2950 4600)(-2950 4550);
WIRE 16 -1 (-2750 4550)(-2950 4550);
WIRE 16 -1 (-2950 4550)(-2950 4500);
WIRE 16 -1 (-2750 4500)(-2950 4500);
WIRE 16 -1 (-2950 4500)(-2950 4450);
WIRE 16 -1 (-2750 4450)(-2950 4450);
WIRE 16 -1 (-2950 4450)(-2950 4400);
WIRE 16 -1 (-2750 4400)(-2950 4400);
WIRE 16 -1 (-2950 4400)(-2950 4350);
WIRE 16 -1 (-2750 4350)(-2950 4350);
WIRE 16 -1 (-2950 4350)(-2950 4300);
WIRE 16 -1 (-2750 4300)(-2950 4300);
WIRE 16 -1 (-2950 4300)(-2950 4250);
WIRE 16 -1 (-2750 4250)(-2950 4250);
WIRE 16 -1 (-2950 4250)(-2950 4200);
WIRE 16 -1 (-2750 4200)(-2950 4200);
WIRE 16 -1 (-2950 4200)(-2950 4150);
WIRE 16 -1 (-2750 4150)(-2950 4150);
WIRE 16 -1 (-2950 4150)(-2950 4100);
WIRE 16 -1 (-2750 4100)(-2950 4100);
WIRE 16 -1 (-2950 4100)(-2950 4050);
WIRE 16 -1 (-2750 4050)(-2950 4050);
WIRE 16 -1 (-2950 4050)(-2950 4000);
WIRE 16 -1 (-2750 4000)(-2950 4000);
WIRE 16 -1 (-2950 4000)(-2950 3950);
WIRE 16 -1 (-2750 3950)(-2950 3950);
WIRE 16 -1 (-2950 3950)(-2950 3900);
WIRE 16 -1 (-2750 3900)(-2950 3900);
WIRE 16 -1 (-2950 3900)(-2950 3850);
WIRE 16 -1 (-2750 3850)(-2950 3850);
WIRE 16 -1 (-2950 3850)(-2950 3800);
WIRE 16 -1 (-2750 3800)(-2950 3800);
WIRE 16 -1 (-2950 3800)(-2950 3750);
WIRE 16 -1 (-2750 3750)(-2950 3750);
WIRE 16 -1 (-2950 3750)(-2950 3700);
WIRE 16 -1 (-2750 3700)(-2950 3700);
WIRE 16 -1 (-2950 3700)(-2950 3650);
WIRE 16 -1 (-2750 3650)(-2950 3650);
WIRE 16 -1 (-2950 3650)(-2950 3600);
WIRE 16 -1 (-2750 3600)(-2950 3600);
WIRE 16 -1 (-2950 3600)(-2950 3550);
WIRE 16 -1 (-2750 3550)(-2950 3550);
WIRE 16 -1 (-2950 3550)(-2950 3500);
WIRE 16 -1 (-2750 3500)(-2950 3500);
WIRE 16 -1 (-2950 3500)(-2950 3450);
WIRE 16 -1 (-2750 3450)(-2950 3450);
WIRE 16 -1 (-2950 3450)(-2950 3400);
WIRE 16 -1 (-2750 3400)(-2950 3400);
WIRE 16 -1 (-2950 3400)(-2950 3350);
WIRE 16 -1 (-2750 3350)(-2950 3350);
WIRE 16 -1 (-2950 3350)(-2950 3300);
WIRE 16 -1 (-2750 3300)(-2950 3300);
WIRE 16 -1 (-2950 3300)(-2950 3250);
WIRE 16 -1 (-2750 3250)(-2950 3250);
WIRE 16 -1 (-2950 3250)(-2950 3200);
WIRE 16 -1 (-2750 3200)(-2950 3200);
WIRE 16 -1 (-2950 3200)(-2950 3150);
WIRE 16 -1 (-2750 3150)(-2950 3150);
WIRE 16 -1 (-2950 3150)(-2950 3100);
WIRE 16 -1 (-2750 3100)(-2950 3100);
WIRE 16 -1 (-2950 3100)(-2950 3050);
WIRE 16 -1 (-2750 3050)(-2950 3050);
WIRE 16 -1 (-2950 3050)(-2950 3000);
WIRE 16 -1 (-2750 3000)(-2950 3000);
WIRE 16 -1 (-2950 3000)(-2950 2950);
WIRE 16 -1 (-2750 2950)(-2950 2950);
WIRE 16 -1 (-2950 2950)(-2950 2900);
WIRE 16 -1 (-2750 2900)(-2950 2900);
WIRE 16 -1 (-2950 2900)(-2950 2850);
WIRE 16 -1 (-2750 2850)(-2950 2850);
WIRE 16 -1 (-2950 2850)(-2950 2800);
WIRE 16 -1 (-2750 2800)(-2950 2800);
WIRE 16 -1 (-2950 2800)(-2950 2750);
WIRE 16 -1 (-2750 2750)(-2950 2750);
WIRE 16 -1 (-2950 2750)(-2950 2700);
WIRE 16 -1 (-2750 2700)(-2950 2700);
WIRE 16 -1 (-2950 2700)(-2950 2650);
WIRE 16 -1 (-2750 2650)(-2950 2650);
WIRE 16 -1 (-2950 2650)(-2950 2600);
WIRE 16 -1 (-2750 2600)(-2950 2600);
WIRE 16 -1 (-2950 2600)(-2950 2550);
WIRE 16 -1 (-2750 2550)(-2950 2550);
WIRE 16 -1 (-2950 2550)(-2950 2500);
WIRE 16 -1 (-2750 2500)(-2950 2500);
WIRE 16 -1 (-2950 2500)(-2950 2450);
WIRE 16 -1 (-2750 2450)(-2950 2450);
WIRE 16 -1 (-2950 2450)(-2950 2400);
WIRE 16 -1 (-2750 2400)(-2950 2400);
WIRE 16 -1 (-2950 2400)(-2950 2350);
WIRE 16 -1 (-2750 2350)(-2950 2350);
WIRE 16 -1 (-2950 2350)(-2950 2300);
WIRE 16 -1 (-2750 2300)(-2950 2300);
WIRE 16 -1 (-2950 2300)(-2950 2250);
WIRE 16 -1 (-2750 2250)(-2950 2250);
WIRE 16 -1 (-2950 2250)(-2950 2200);
WIRE 16 -1 (-2750 2200)(-2950 2200);
WIRE 16 -1 (-2950 2200)(-2950 2150);
WIRE 16 -1 (-2750 2150)(-2950 2150);
WIRE 16 -1 (-2950 2150)(-2950 2100);
WIRE 16 -1 (-2750 2100)(-2950 2100);
WIRE 16 -1 (-2950 2100)(-2950 2050);
WIRE 16 -1 (-2750 2050)(-2950 2050);
WIRE 16 -1 (-2950 2050)(-2950 2000);
WIRE 16 -1 (-2750 2000)(-2950 2000);
WIRE 16 -1 (-2950 2000)(-2950 1950);
WIRE 16 -1 (-2750 1950)(-2950 1950);
WIRE 16 -1 (-2950 1950)(-2950 1900);
WIRE 16 -1 (-2750 1900)(-2950 1900);
WIRE 16 -1 (-2950 1900)(-2950 1850);
WIRE 16 -1 (-2750 1850)(-2950 1850);
WIRE 16 -1 (-2950 1850)(-2950 1800);
WIRE 16 -1 (-2750 1800)(-2950 1800);
WIRE 16 -1 (-2950 1800)(-2950 1750);
WIRE 16 -1 (-2750 1750)(-2950 1750);
WIRE 16 -1 (-2950 1750)(-2950 1700);
WIRE 16 -1 (-2750 1700)(-2950 1700);
WIRE 16 -1 (-2950 1700)(-2950 1650);
WIRE 16 -1 (-2750 1650)(-2950 1650);
WIRE 16 -1 (-2950 1650)(-2950 1600);
WIRE 16 -1 (-2750 1600)(-2950 1600);
WIRE 16 -1 (-2950 1600)(-2950 1550);
WIRE 16 -1 (-2750 1550)(-2950 1550);
WIRE 16 -1 (-2950 1550)(-2950 1400);
WIRE 16 -1 (-1275 2050)(-1800 2050);
FORCEPROP 2 LAST SIG_NAME NCF_CPU1_P1_GND
J 0
(-1685 2060);
DISPLAY 0.553191 (-1685 2060);
FORCEPROP 2 LASTPROP $XRERR UNIQUE?
J 0
(-1925 2060);
DISPLAY 0.638298 (-1925 2060);
PAINT MONO (-1925 2060);
DISPLAY INVISIBLE (-1925 2060);
WIRE 16 -1 (-1275 2050)(-1275 2000);
WIRE 16 -1 (-1275 2000)(-1275 1950);
WIRE 16 -1 (-1275 2000)(-1800 2000);
WIRE 16 -1 (-1275 1950)(-1275 1900);
WIRE 16 -1 (-1275 1950)(-1800 1950);
WIRE 16 -1 (-1275 1900)(-1275 1850);
WIRE 16 -1 (-1275 1900)(-1800 1900);
WIRE 16 -1 (-1275 1850)(-1275 1800);
WIRE 16 -1 (-1275 1850)(-1800 1850);
WIRE 16 -1 (-1275 1800)(-1275 1750);
WIRE 16 -1 (-1275 1800)(-1800 1800);
WIRE 16 -1 (-1275 1750)(-1275 1700);
WIRE 16 -1 (-1275 1750)(-1800 1750);
WIRE 16 -1 (-1275 1700)(-1275 1650);
WIRE 16 -1 (-1275 1700)(-1800 1700);
WIRE 16 -1 (-1275 1650)(-1275 1600);
WIRE 16 -1 (-1275 1650)(-1800 1650);
WIRE 16 -1 (-1275 1600)(-1275 1550);
WIRE 16 -1 (-1275 1600)(-1800 1600);
WIRE 16 -1 (-1275 1550)(-1275 1375);
WIRE 16 -1 (-1275 1550)(-1800 1550);
WIRE 16 -1 (-1600 2250)(-1600 2200);
WIRE 16 -1 (-1600 2300)(-1600 2250);
WIRE 16 -1 (-1600 2250)(-1800 2250);
WIRE 16 -1 (-1600 2200)(-1600 2175);
WIRE 16 -1 (-1600 2200)(-1800 2200);
WIRE 16 -1 (-1600 2175)(-900 2175);
WIRE 16 -1 (-1600 2350)(-1600 2300);
WIRE 16 -1 (-1600 2300)(-1800 2300);
WIRE 16 -1 (-1600 2400)(-1600 2350);
WIRE 16 -1 (-1600 2350)(-1800 2350);
WIRE 16 -1 (-900 2175)(-900 2125);
WIRE 16 -1 (-1600 2450)(-1600 2400);
WIRE 16 -1 (-1600 2400)(-1800 2400);
WIRE 16 -1 (-1600 2500)(-1600 2450);
WIRE 16 -1 (-1600 2450)(-1800 2450);
WIRE 16 -1 (-1600 2550)(-1600 2500);
WIRE 16 -1 (-1600 2500)(-1800 2500);
WIRE 16 -1 (-1600 2600)(-1600 2550);
WIRE 16 -1 (-1600 2550)(-1800 2550);
WIRE 16 -1 (-1600 2650)(-1600 2600);
WIRE 16 -1 (-1600 2600)(-1800 2600);
WIRE 16 -1 (-1600 2700)(-1600 2650);
WIRE 16 -1 (-1600 2650)(-1800 2650);
WIRE 16 -1 (-1600 2750)(-1600 2700);
WIRE 16 -1 (-1600 2700)(-1800 2700);
WIRE 16 -1 (-1600 2800)(-1600 2750);
WIRE 16 -1 (-1600 2750)(-1800 2750);
WIRE 16 -1 (-1600 2850)(-1600 2800);
WIRE 16 -1 (-1600 2800)(-1800 2800);
WIRE 16 -1 (-1600 2900)(-1600 2850);
WIRE 16 -1 (-1600 2850)(-1800 2850);
WIRE 16 -1 (-1600 2950)(-1600 2900);
WIRE 16 -1 (-1600 2900)(-1800 2900);
WIRE 16 -1 (-1600 3000)(-1600 2950);
WIRE 16 -1 (-1600 2950)(-1800 2950);
WIRE 16 -1 (-1600 3050)(-1600 3000);
WIRE 16 -1 (-1600 3000)(-1800 3000);
WIRE 16 -1 (-1600 3100)(-1600 3050);
WIRE 16 -1 (-1600 3050)(-1800 3050);
WIRE 16 -1 (-1600 3150)(-1600 3100);
WIRE 16 -1 (-1600 3100)(-1800 3100);
WIRE 16 -1 (-1600 3200)(-1600 3150);
WIRE 16 -1 (-1600 3150)(-1800 3150);
WIRE 16 -1 (-1600 3250)(-1600 3200);
WIRE 16 -1 (-1600 3200)(-1800 3200);
WIRE 16 -1 (-1600 3300)(-1600 3250);
WIRE 16 -1 (-1600 3250)(-1800 3250);
WIRE 16 -1 (-1600 3350)(-1600 3300);
WIRE 16 -1 (-1600 3300)(-1800 3300);
WIRE 16 -1 (-1600 3400)(-1600 3350);
WIRE 16 -1 (-1600 3350)(-1800 3350);
WIRE 16 -1 (-1600 3450)(-1600 3400);
WIRE 16 -1 (-1600 3400)(-1800 3400);
WIRE 16 -1 (-1600 3500)(-1600 3450);
WIRE 16 -1 (-1600 3450)(-1800 3450);
WIRE 16 -1 (-1600 3550)(-1600 3500);
WIRE 16 -1 (-1600 3500)(-1800 3500);
WIRE 16 -1 (-1600 3600)(-1600 3550);
WIRE 16 -1 (-1600 3550)(-1800 3550);
WIRE 16 -1 (-1600 3650)(-1600 3600);
WIRE 16 -1 (-1600 3600)(-1800 3600);
WIRE 16 -1 (-1600 3700)(-1600 3650);
WIRE 16 -1 (-1600 3650)(-1800 3650);
WIRE 16 -1 (-1600 3750)(-1600 3700);
WIRE 16 -1 (-1600 3700)(-1800 3700);
WIRE 16 -1 (-1600 3800)(-1600 3750);
WIRE 16 -1 (-1600 3750)(-1800 3750);
WIRE 16 -1 (-1600 3850)(-1600 3800);
WIRE 16 -1 (-1600 3800)(-1800 3800);
WIRE 16 -1 (-1600 3900)(-1600 3850);
WIRE 16 -1 (-1600 3850)(-1800 3850);
WIRE 16 -1 (-1600 3950)(-1600 3900);
WIRE 16 -1 (-1600 3900)(-1800 3900);
WIRE 16 -1 (-1600 4000)(-1600 3950);
WIRE 16 -1 (-1600 3950)(-1800 3950);
WIRE 16 -1 (-1600 4050)(-1600 4000);
WIRE 16 -1 (-1600 4000)(-1800 4000);
WIRE 16 -1 (-1600 4100)(-1600 4050);
WIRE 16 -1 (-1600 4050)(-1800 4050);
WIRE 16 -1 (-1600 4150)(-1600 4100);
WIRE 16 -1 (-1600 4100)(-1800 4100);
WIRE 16 -1 (-1600 4200)(-1600 4150);
WIRE 16 -1 (-1600 4150)(-1800 4150);
WIRE 16 -1 (-1600 4250)(-1600 4200);
WIRE 16 -1 (-1600 4200)(-1800 4200);
WIRE 16 -1 (-1600 4300)(-1600 4250);
WIRE 16 -1 (-1600 4250)(-1800 4250);
WIRE 16 -1 (-1600 4350)(-1600 4300);
WIRE 16 -1 (-1600 4300)(-1800 4300);
WIRE 16 -1 (-1600 4400)(-1600 4350);
WIRE 16 -1 (-1600 4350)(-1800 4350);
WIRE 16 -1 (-1600 4450)(-1600 4400);
WIRE 16 -1 (-1600 4400)(-1800 4400);
WIRE 16 -1 (-1600 4500)(-1600 4450);
WIRE 16 -1 (-1600 4450)(-1800 4450);
WIRE 16 -1 (-1600 4550)(-1600 4500);
WIRE 16 -1 (-1600 4500)(-1800 4500);
WIRE 16 -1 (-1600 4600)(-1600 4550);
WIRE 16 -1 (-1600 4550)(-1800 4550);
WIRE 16 -1 (-1600 4650)(-1600 4600);
WIRE 16 -1 (-1600 4600)(-1800 4600);
WIRE 16 -1 (-1600 4700)(-1600 4650);
WIRE 16 -1 (-1600 4650)(-1800 4650);
WIRE 16 -1 (-1600 4750)(-1600 4700);
WIRE 16 -1 (-1600 4700)(-1800 4700);
WIRE 16 -1 (-1600 4800)(-1600 4750);
WIRE 16 -1 (-1600 4750)(-1800 4750);
WIRE 16 -1 (-1600 4850)(-1600 4800);
WIRE 16 -1 (-1600 4800)(-1800 4800);
WIRE 16 -1 (-1600 4900)(-1600 4850);
WIRE 16 -1 (-1600 4850)(-1800 4850);
WIRE 16 -1 (-1600 4950)(-1600 4900);
WIRE 16 -1 (-1600 4900)(-1800 4900);
WIRE 16 -1 (-1600 5000)(-1600 4950);
WIRE 16 -1 (-1600 4950)(-1800 4950);
WIRE 16 -1 (-1600 5050)(-1600 5000);
WIRE 16 -1 (-1600 5000)(-1800 5000);
WIRE 16 -1 (-1600 5100)(-1600 5050);
WIRE 16 -1 (-1600 5050)(-1800 5050);
WIRE 16 -1 (-1600 5150)(-1600 5100);
WIRE 16 -1 (-1600 5100)(-1800 5100);
WIRE 16 -1 (-1600 5200)(-1600 5150);
WIRE 16 -1 (-1600 5150)(-1800 5150);
WIRE 16 -1 (-1600 5250)(-1600 5200);
WIRE 16 -1 (-1600 5200)(-1800 5200);
WIRE 16 -1 (-1600 5300)(-1600 5250);
WIRE 16 -1 (-1600 5250)(-1800 5250);
WIRE 16 -1 (-1600 5350)(-1600 5300);
WIRE 16 -1 (-1600 5300)(-1800 5300);
WIRE 16 -1 (-1600 5400)(-1600 5350);
WIRE 16 -1 (-1600 5350)(-1800 5350);
WIRE 16 -1 (-1600 5450)(-1600 5400);
WIRE 16 -1 (-1600 5400)(-1800 5400);
WIRE 16 -1 (-1600 5500)(-1600 5450);
WIRE 16 -1 (-1600 5450)(-1800 5450);
WIRE 16 -1 (-1600 5550)(-1600 5500);
WIRE 16 -1 (-1600 5500)(-1800 5500);
WIRE 16 -1 (-1600 5600)(-1600 5550);
WIRE 16 -1 (-1600 5550)(-1800 5550);
WIRE 16 -1 (-1600 5600)(-1800 5600);
WIRE 16 -1 (-5525 3925)(-5525 3875);
WIRE 16 -1 (-5525 3975)(-5525 3925);
WIRE 16 -1 (-5775 3925)(-5525 3925);
WIRE 16 -1 (-5525 3875)(-5525 3825);
WIRE 16 -1 (-5775 3875)(-5525 3875);
WIRE 16 -1 (-5525 3825)(-5775 3825);
WIRE 16 -1 (-5525 4025)(-5525 3975);
WIRE 16 -1 (-5775 3975)(-5525 3975);
WIRE 16 -1 (-5525 4075)(-5525 4025);
WIRE 16 -1 (-5775 4025)(-5525 4025);
WIRE 16 -1 (-5525 4125)(-5525 4075);
WIRE 16 -1 (-5775 4075)(-5525 4075);
WIRE 16 -1 (-5525 4175)(-5525 4125);
WIRE 16 -1 (-5775 4125)(-5525 4125);
WIRE 16 -1 (-5525 4225)(-5525 4175);
WIRE 16 -1 (-5775 4175)(-5525 4175);
WIRE 16 -1 (-5525 4275)(-5525 4225);
WIRE 16 -1 (-5775 4225)(-5525 4225);
WIRE 16 -1 (-5525 4275)(-4500 4275);
WIRE 16 -1 (-5525 4275)(-5775 4275);
WIRE 16 -1 (-4500 4775)(-4500 4275);
WIRE 16 -1 (-5550 4775)(-4500 4775);
WIRE 16 -1 (-4500 4775)(-4500 5000);
WIRE 16 -1 (-5775 4775)(-5550 4775);
WIRE 16 -1 (-5550 4775)(-5550 4725);
WIRE 16 -1 (-5550 4725)(-5550 4675);
WIRE 16 -1 (-5775 4725)(-5550 4725);
WIRE 16 -1 (-5550 4675)(-5550 4625);
WIRE 16 -1 (-5775 4675)(-5550 4675);
WIRE 16 -1 (-5550 4625)(-5550 4575);
WIRE 16 -1 (-5775 4625)(-5550 4625);
WIRE 16 -1 (-5550 4575)(-5550 4525);
WIRE 16 -1 (-5775 4575)(-5550 4575);
WIRE 16 -1 (-5550 4525)(-5775 4525);
WIRE 16 -1 (-5525 4425)(-5525 4375);
WIRE 16 -1 (-5525 4475)(-5525 4425);
WIRE 16 -1 (-5775 4425)(-5525 4425);
WIRE 16 -1 (-5525 4375)(-5525 4325);
WIRE 16 -1 (-5525 4375)(-5775 4375);
WIRE 16 -1 (-5525 4325)(-5775 4325);
WIRE 16 -1 (-5525 4475)(-5075 4475);
WIRE 16 -1 (-5775 4475)(-5525 4475);
WIRE 16 -1 (-5075 4475)(-5075 4525);
WIRE 16 -1 (-1800 2100)(-1125 2100);
FORCEPROP 2 LAST SIG_NAME NCF_A1_CPU1_P1_GND
J 0
(-1635 2110);
DISPLAY 0.553191 (-1635 2110);
FORCEPROP 2 LASTPROP $XRERR UNIQUE?
J 0
(-1875 2110);
DISPLAY 0.638298 (-1875 2110);
PAINT MONO (-1875 2110);
DISPLAY INVISIBLE (-1875 2110);
WIRE 16 -1 (-1125 2100)(-1125 1925);
WIRE 16 -1 (-5450 3625)(-5450 3575);
WIRE 16 -1 (-5450 3675)(-5450 3625);
WIRE 16 -1 (-5775 3625)(-5450 3625);
WIRE 16 -1 (-5450 3575)(-5450 3525);
WIRE 16 -1 (-5775 3575)(-5450 3575);
WIRE 16 -1 (-5450 3525)(-5775 3525);
WIRE 16 -1 (-5450 3675)(-4475 3675);
WIRE 16 -1 (-5775 3675)(-5450 3675);
WIRE 16 -1 (-4475 3775)(-4475 3675);
DOT 1 (-7475 3675);
DOT 1 (-2950 1850);
DOT 1 (-1275 1800);
DOT 1 (-1275 1900);
DOT 1 (-1600 4500);
DOT 1 (-1600 4600);
DOT 1 (-1600 4750);
DOT 1 (-1600 4700);
DOT 1 (-1600 4650);
DOT 1 (-5525 4275);
DOT 1 (-1600 5550);
DOT 1 (-1600 5450);
DOT 1 (-1600 5400);
DOT 1 (-1600 5350);
DOT 1 (-1600 5300);
DOT 1 (-1600 5250);
DOT 1 (-1600 5200);
DOT 1 (-1600 5150);
DOT 1 (-1600 5100);
DOT 1 (-1600 5050);
DOT 1 (-1600 5000);
DOT 1 (-1600 4950);
DOT 1 (-1600 4900);
DOT 1 (-1600 4850);
DOT 1 (-1600 4800);
DOT 1 (-1600 4450);
DOT 1 (-1600 4400);
DOT 1 (-1600 4350);
DOT 1 (-1600 4300);
DOT 1 (-1600 4250);
DOT 1 (-1600 4200);
DOT 1 (-1600 4150);
DOT 1 (-1600 4100);
DOT 1 (-1600 4050);
DOT 1 (-1600 4000);
DOT 1 (-1600 3950);
DOT 1 (-1600 3850);
DOT 1 (-2950 5550);
DOT 1 (-2950 5500);
DOT 1 (-2950 5450);
DOT 1 (-2950 5400);
DOT 1 (-2950 5350);
DOT 1 (-2950 5300);
DOT 1 (-2950 5250);
DOT 1 (-2950 5200);
DOT 1 (-2950 5150);
DOT 1 (-2950 5100);
DOT 1 (-2950 5000);
DOT 1 (-2950 5050);
DOT 1 (-2950 4850);
DOT 1 (-2950 4950);
DOT 1 (-2950 4900);
DOT 1 (-2950 4750);
DOT 1 (-2950 4800);
DOT 1 (-2950 4600);
DOT 1 (-2950 4650);
DOT 1 (-2950 4700);
DOT 1 (-2950 4550);
DOT 1 (-2950 4500);
DOT 1 (-2950 4450);
DOT 1 (-2950 4350);
DOT 1 (-2950 4400);
DOT 1 (-2950 4300);
DOT 1 (-2950 4250);
DOT 1 (-2950 4200);
DOT 1 (-2950 4100);
DOT 1 (-2950 4150);
DOT 1 (-2950 4000);
DOT 1 (-2950 4050);
DOT 1 (-2950 3950);
DOT 1 (-2950 3850);
DOT 1 (-2950 3900);
DOT 1 (-1600 3800);
DOT 1 (-1600 3750);
DOT 1 (-1600 3700);
DOT 1 (-1600 3600);
DOT 1 (-1600 3650);
DOT 1 (-1600 3550);
DOT 1 (-1600 3500);
DOT 1 (-1600 3450);
DOT 1 (-1600 3350);
DOT 1 (-1600 3400);
DOT 1 (-1600 3300);
DOT 1 (-1600 3250);
DOT 1 (-1600 3200);
DOT 1 (-1600 3100);
DOT 1 (-1600 3150);
DOT 1 (-1600 3050);
DOT 1 (-1600 3000);
DOT 1 (-1600 2950);
DOT 1 (-1600 2900);
DOT 1 (-1600 2850);
DOT 1 (-1600 2800);
DOT 1 (-1600 2700);
DOT 1 (-1600 2750);
DOT 1 (-1600 2650);
DOT 1 (-1600 2600);
DOT 1 (-1600 2550);
DOT 1 (-1600 2450);
DOT 1 (-1600 2500);
DOT 1 (-1600 2400);
DOT 1 (-1600 2350);
DOT 1 (-1600 2300);
DOT 1 (-1600 2200);
DOT 1 (-1275 1750);
DOT 1 (-1275 1700);
DOT 1 (-1275 1650);
DOT 1 (-1275 1550);
DOT 1 (-1275 1600);
DOT 1 (-2950 3750);
DOT 1 (-2950 3800);
DOT 1 (-2950 3700);
DOT 1 (-2950 3650);
DOT 1 (-2950 3600);
DOT 1 (-2950 3550);
DOT 1 (-2950 3450);
DOT 1 (-2950 3500);
DOT 1 (-2950 3350);
DOT 1 (-2950 3400);
DOT 1 (-2950 3300);
DOT 1 (-2950 3200);
DOT 1 (-2950 3250);
DOT 1 (-2950 3150);
DOT 1 (-2950 3050);
DOT 1 (-2950 3100);
DOT 1 (-2950 2950);
DOT 1 (-2950 3000);
DOT 1 (-2950 2800);
DOT 1 (-2950 2900);
DOT 1 (-2950 2850);
DOT 1 (-2950 2700);
DOT 1 (-2950 2750);
DOT 1 (-2950 2650);
DOT 1 (-2950 2600);
DOT 1 (-2950 2550);
DOT 1 (-2950 2500);
DOT 1 (-2950 2450);
DOT 1 (-2950 2400);
DOT 1 (-2950 2300);
DOT 1 (-2950 2350);
DOT 1 (-2950 2200);
DOT 1 (-2950 2250);
DOT 1 (-2950 2150);
DOT 1 (-2950 2050);
DOT 1 (-2950 2100);
DOT 1 (-2950 1950);
DOT 1 (-2950 2000);
DOT 1 (-2950 1900);
DOT 1 (-2950 1800);
DOT 1 (-2950 1700);
DOT 1 (-2950 1750);
DOT 1 (-2950 1650);
DOT 1 (-2950 1600);
DOT 1 (-2950 1550);
DOT 1 (-4500 4775);
DOT 1 (-5550 4675);
DOT 1 (-5525 4375);
DOT 1 (-5525 4075);
DOT 1 (-5525 3975);
DOT 1 (-5525 4025);
DOT 1 (-5525 3925);
DOT 1 (-7350 4725);
DOT 1 (-7350 4775);
DOT 1 (-5450 3625);
DOT 1 (-5450 3675);
DOT 1 (-5450 3575);
DOT 1 (-5525 4425);
DOT 1 (-5550 4575);
DOT 1 (-5550 4625);
DOT 1 (-1600 5500);
DOT 1 (-1600 4550);
DOT 1 (-1600 3900);
DOT 1 (-1275 2000);
DOT 1 (-1275 1950);
DOT 1 (-1275 1850);
DOT 1 (-5550 4725);
DOT 1 (-5525 4225);
DOT 1 (-5525 3875);
DOT 1 (-7350 4625);
DOT 1 (-7350 4675);
DOT 1 (-5525 4475);
DOT 1 (-5550 4775);
DOT 1 (-5525 4175);
DOT 1 (-5525 4125);
DOT 1 (-1600 2250);
QUIT
